# BASEBOARD_FAB2 (Tioga Pass) — schematic netlist excerpt (pin names and nets, part order shuffled) for the footprints in the layout excerpt that follows; sources: Cadence DE-HDL packaged netlist, KiCad conversion of Wiwynn_Tioga_Pass_MB.brd

C3P41  CAP  0.22UF 16V 10% X7R  pkg 0402  page 107 : A = P3E_CPU0_PE1_SS_TXN<7> ; B = P3E_CPU0_PE1_SS_C_TXN<7>

Q7D1  FET_N  2N7002 FET  pkg SOT23LF  page 134
  GATE  = FM_THERMTRIP_DLY_R
  SRC  = GND
  DRN  = FM_PCH_LVC1_THERMTRIP_N

R7E21  RES  4.75K 1% CHIP  pkg 0402  page 108 : A = P3V3 ; B = FM_PWRBRK_N

(kicad_pcb
	(version 20260206)
	(generator "pcbnew")
	(generator_version "10.0")
	(general
		(thickness 1.6)
		(legacy_teardrops no)
	)
	(paper "A4")
	(title_block
		(title "Wiwynn_Tioga_Pass_MB.brd")
		(comment 1 "Tioga Pass / footprints 4037-4039 of 4770")
	)
	(layers
		(0 "F.Cu" signal "TOP")
		(4 "In1.Cu" signal "L2GND")
		(6 "In2.Cu" signal "L3")
		(8 "In3.Cu" signal "L4GND")
		(10 "In4.Cu" signal "L5")
		(12 "In5.Cu" signal "L6GND")
		(14 "In6.Cu" signal "L7VCC")
		(16 "In7.Cu" signal "L8VCC")
		(18 "In8.Cu" signal "L9GND")
		(20 "In9.Cu" signal "L10")
		(22 "In10.Cu" signal "L11GND")
		(24 "In11.Cu" signal "L12")
		(26 "In12.Cu" signal "L13GND")
		(2 "B.Cu" signal "BOTTOM")
		(9 "F.Adhes" user "F.Adhesive")
		(11 "B.Adhes" user "B.Adhesive")
		(13 "F.Paste" user "Package Geometry/Pastemask Top")
		(15 "B.Paste" user "Package Geometry/Pastemask Bottom")
		(5 "F.SilkS" user "Ref Des/Silkscreen Top")
		(7 "B.SilkS" user "Ref Des/Silkscreen Bottom")
		(1 "F.Mask" user "Board Geometry/Soldermask Top")
		(3 "B.Mask" user "Board Geometry/Soldermask Bottom")
		(17 "Dwgs.User" user "User.Drawings")
		(19 "Cmts.User" user "User.Comments")
		(21 "Eco1.User" user "User.Eco1")
		(23 "Eco2.User" user "User.Eco2")
		(25 "Edge.Cuts" user "Board Geometry/Outline")
		(27 "Margin" user)
		(31 "F.CrtYd" user "Package Geometry/Place Bound Top")
		(29 "B.CrtYd" user "Package Geometry/Place Bound Bottom")
		(35 "F.Fab" user "Ref Des/Assembly Top")
		(33 "B.Fab" user "Ref Des/Assembly Bottom")
	)
	(footprint ""
		(layer "B.Cu")
		(at 468.58809 -6.011672)
		(property "Reference" "R7E21"
			(at 0 0 0)
			(layer "B.SilkS")
			(hide yes)
			(effects
				(font
					(size 1.27 1.27)
				)
				(justify mirror)
			)
		)
		(property "Value" ""
			(at 0 0 0)
			(layer "B.Fab")
			(effects
				(font
					(size 1.27 1.27)
				)
				(justify mirror)
			)
		)
		(duplicate_pad_numbers_are_jumpers no)
		(fp_poly
			(pts
				(xy 0.2794 -0.1016) (xy -0.2794 -0.1016) (xy -0.2794 0.9906) (xy 0.2794 0.9906)
			)
			(stroke
				(width 0)
				(type default)
			)
			(fill no)
			(layer "B.CrtYd")
		)
		(fp_line
			(start -0.2794 -0.1016)
			(end 0.2794 -0.1016)
			(stroke
				(width 0.1)
				(type default)
			)
			(layer "B.Fab")
		)
		(fp_line
			(start -0.2794 0.9906)
			(end -0.2794 -0.1016)
			(stroke
				(width 0.1)
				(type default)
			)
			(layer "B.Fab")
		)
		(fp_line
			(start 0.2794 -0.1016)
			(end 0.2794 0.9906)
			(stroke
				(width 0.1)
				(type default)
			)
			(layer "B.Fab")
		)
		(fp_line
			(start 0.2794 0.9906)
			(end -0.2794 0.9906)
			(stroke
				(width 0.1)
				(type default)
			)
			(layer "B.Fab")
		)
		(pad "1" smd rect
			(at 0 0 180)
			(size 0.508 0.508)
			(layers "B.Cu" "B.Mask" "B.Paste")
			(net "P3V3")
		)
		(pad "2" smd rect
			(at 0 0.889 180)
			(size 0.508 0.508)
			(layers "B.Cu" "B.Mask" "B.Paste")
			(net "FM_PWRBRK_N")
		)
		(zone
			(layer "B.Cu")
			(hatch none 0.5)
			(connect_pads
				(clearance 0)
			)
			(min_thickness 0.25)
			(keepout
				(tracks allowed)
				(vias not_allowed)
				(pads allowed)
				(copperpour not_allowed)
				(footprints allowed)
			)
			(placement
				(enabled no)
				(sheetname "")
			)
			(fill
				(thermal_gap 0.5)
				(thermal_bridge_width 0.5)
				(island_removal_mode 0)
			)
			(polygon
				(pts
					(xy 468.84209 -5.757672) (xy 468.33409 -5.757672) (xy 468.33409 -5.376672) (xy 468.84209 -5.376672)
				)
			)
		)
		(zone
			(layer "B.Cu")
			(hatch none 0.5)
			(connect_pads
				(clearance 0)
			)
			(min_thickness 0.25)
			(keepout
				(tracks not_allowed)
				(vias allowed)
				(pads allowed)
				(copperpour not_allowed)
				(footprints allowed)
			)
			(placement
				(enabled no)
				(sheetname "")
			)
			(fill
				(thermal_gap 0.5)
				(thermal_bridge_width 0.5)
				(island_removal_mode 0)
			)
			(polygon
				(pts
					(xy 468.84209 -5.376672) (xy 468.33409 -5.376672) (xy 468.33409 -5.757672) (xy 468.84209 -5.757672)
				)
			)
		)
	)
	(footprint ""
		(layer "B.Cu")
		(at 375.991374 -83.86953 -90)
		(property "Reference" "Q7D1"
			(at 0.229362 -1.2065 270)
			(unlocked yes)
			(layer "B.SilkS")
			(effects
				(font
					(size 0.4064 0.254)
					(thickness 0.1524)
				)
				(justify left mirror)
			)
		)
		(property "Value" ""
			(at 0 0 90)
			(layer "B.Fab")
			(effects
				(font
					(size 1.27 1.27)
				)
				(justify mirror)
			)
		)
		(duplicate_pad_numbers_are_jumpers no)
		(fp_line
			(start -1.778 2.4765)
			(end -1.778 1.5875)
			(stroke
				(width 0.1524)
				(type default)
			)
			(layer "B.SilkS")
		)
		(fp_line
			(start -0.9525 2.4765)
			(end -1.778 2.4765)
			(stroke
				(width 0.1524)
				(type default)
			)
			(layer "B.SilkS")
		)
		(fp_line
			(start -0.381 0.635)
			(end -0.381 1.27)
			(stroke
				(width 0.1524)
				(type default)
			)
			(layer "B.SilkS")
		)
		(fp_line
			(start -1.778 -0.5715)
			(end -1.778 0.3175)
			(stroke
				(width 0.1524)
				(type default)
			)
			(layer "B.SilkS")
		)
		(fp_line
			(start -0.9525 -0.5715)
			(end -1.778 -0.5715)
			(stroke
				(width 0.1524)
				(type default)
			)
			(layer "B.SilkS")
		)
		(fp_circle
			(center 0.9525 -0.9271)
			(end 0.9525 -1.0541)
			(stroke
				(width 0.254)
				(type default)
			)
			(fill no)
			(layer "B.SilkS")
		)
		(fp_poly
			(pts
				(xy -1.778 2.4765) (xy -0.381 2.4765) (xy -0.381 -0.5715) (xy -1.778 -0.5715)
			)
			(stroke
				(width 0)
				(type default)
			)
			(fill no)
			(layer "B.CrtYd")
		)
		(fp_line
			(start -1.778 2.4765)
			(end -1.778 -0.5715)
			(stroke
				(width 0.1)
				(type default)
			)
			(layer "B.Fab")
		)
		(fp_line
			(start -0.381 2.4765)
			(end -1.778 2.4765)
			(stroke
				(width 0.1)
				(type default)
			)
			(layer "B.Fab")
		)
		(fp_line
			(start -1.778 -0.5715)
			(end -0.381 -0.5715)
			(stroke
				(width 0.1)
				(type default)
			)
			(layer "B.Fab")
		)
		(fp_line
			(start -0.381 -0.5715)
			(end -0.381 2.4765)
			(stroke
				(width 0.1)
				(type default)
			)
			(layer "B.Fab")
		)
		(fp_circle
			(center 0.9525 -0.9271)
			(end 0.9525 -1.0541)
			(stroke
				(width 0.254)
				(type default)
			)
			(fill no)
			(layer "B.Fab")
		)
		(pad "1" smd rect
			(at 0 0 90)
			(size 1.143 0.508)
			(layers "B.Cu" "B.Mask" "B.Paste")
			(net "FM_THERMTRIP_DLY_R")
		)
		(pad "2" smd rect
			(at 0 1.905 90)
			(size 1.143 0.508)
			(layers "B.Cu" "B.Mask" "B.Paste")
			(net "GND")
		)
		(pad "3" smd rect
			(at -2.159 0.9525 90)
			(size 1.143 0.508)
			(layers "B.Cu" "B.Mask" "B.Paste")
			(net "FM_PCH_LVC1_THERMTRIP_N")
		)
	)
	(footprint ""
		(layer "B.Cu")
		(at 358.44988 -77.923136)
		(property "Reference" "C3P41"
			(at 0 0 0)
			(layer "B.SilkS")
			(hide yes)
			(effects
				(font
					(size 1.27 1.27)
				)
				(justify mirror)
			)
		)
		(property "Value" ""
			(at 0 0 0)
			(layer "B.Fab")
			(effects
				(font
					(size 1.27 1.27)
				)
				(justify mirror)
			)
		)
		(duplicate_pad_numbers_are_jumpers no)
		(fp_poly
			(pts
				(xy -0.3048 -0.1016) (xy -0.3048 0.9906) (xy 0.3048 0.9906) (xy 0.3048 -0.1016)
			)
			(stroke
				(width 0)
				(type default)
			)
			(fill no)
			(layer "B.CrtYd")
		)
		(fp_line
			(start -0.3048 -0.1016)
			(end 0.3048 -0.1016)
			(stroke
				(width 0.1)
				(type default)
			)
			(layer "B.Fab")
		)
		(fp_line
			(start -0.3048 0.9906)
			(end -0.3048 -0.1016)
			(stroke
				(width 0.1)
				(type default)
			)
			(layer "B.Fab")
		)
		(fp_line
			(start 0.3048 -0.1016)
			(end 0.3048 0.9906)
			(stroke
				(width 0.1)
				(type default)
			)
			(layer "B.Fab")
		)
		(fp_line
			(start 0.3048 0.9906)
			(end -0.3048 0.9906)
			(stroke
				(width 0.1)
				(type default)
			)
			(layer "B.Fab")
		)
		(pad "1" smd rect
			(at 0 0 180)
			(size 0.508 0.508)
			(layers "B.Cu" "B.Mask" "B.Paste")
			(net "P3E_CPU0_PE1_SS_TXN<7>")
		)
		(pad "2" smd rect
			(at 0 0.889 180)
			(size 0.508 0.508)
			(layers "B.Cu" "B.Mask" "B.Paste")
			(net "P3E_CPU0_PE1_SS_C_TXN<7>")
		)
		(zone
			(layer "B.Cu")
			(hatch none 0.5)
			(connect_pads
				(clearance 0)
			)
			(min_thickness 0.25)
			(keepout
				(tracks allowed)
				(vias not_allowed)
				(pads allowed)
				(copperpour not_allowed)
				(footprints allowed)
			)
			(placement
				(enabled no)
				(sheetname "")
			)
			(fill
				(thermal_gap 0.5)
				(thermal_bridge_width 0.5)
				(island_removal_mode 0)
			)
			(polygon
				(pts
					(xy 358.70388 -77.669136) (xy 358.19588 -77.669136) (xy 358.19588 -77.288136) (xy 358.70388 -77.288136)
				)
			)
		)
		(zone
			(layer "B.Cu")
			(hatch none 0.5)
			(connect_pads
				(clearance 0)
			)
			(min_thickness 0.25)
			(keepout
				(tracks not_allowed)
				(vias allowed)
				(pads allowed)
				(copperpour not_allowed)
				(footprints allowed)
			)
			(placement
				(enabled no)
				(sheetname "")
			)
			(fill
				(thermal_gap 0.5)
				(thermal_bridge_width 0.5)
				(island_removal_mode 0)
			)
			(polygon
				(pts
					(xy 358.70388 -77.288136) (xy 358.19588 -77.288136) (xy 358.19588 -77.669136) (xy 358.70388 -77.669136)
				)
			)
		)
	)
)
